(kicad_pcb
	(version 20241229)
	(generator "pcbnew")
	(generator_version "9.0")
	(general
		(thickness 1.62)
		(legacy_teardrops no)
	)
	(paper "A3")
	(title_block
		(title "COM Express 7 Baseboard")
		(date "2025-02-04")
		(rev "1.1.2")
		(company "Antmicro Ltd")
		(comment 1 "www.antmicro.com")
		(comment 9 "footprints 764-769 of 802")
	)
	(layers
		(0 "F.Cu" signal)
		(4 "In1.Cu" signal)
		(6 "In2.Cu" signal)
		(8 "In3.Cu" signal)
		(10 "In4.Cu" signal)
		(12 "In5.Cu" signal)
		(14 "In6.Cu" signal)
		(2 "B.Cu" signal)
		(9 "F.Adhes" user "F.Adhesive")
		(11 "B.Adhes" user "B.Adhesive")
		(13 "F.Paste" user)
		(15 "B.Paste" user)
		(5 "F.SilkS" user "F.Silkscreen")
		(7 "B.SilkS" user "B.Silkscreen")
		(1 "F.Mask" user)
		(3 "B.Mask" user)
		(17 "Dwgs.User" user "User.Drawings")
		(19 "Cmts.User" user "User.Comments")
		(21 "Eco1.User" user "User.Eco1")
		(23 "Eco2.User" user "User.Eco2")
		(25 "Edge.Cuts" user)
		(27 "Margin" user)
		(31 "F.CrtYd" user "F.Courtyard")
		(29 "B.CrtYd" user "B.Courtyard")
		(35 "F.Fab" user)
		(33 "B.Fab" user)
	)
	(footprint "antmicro-footprints:C_0603_1608Metric"
		(layer "B.Cu")
		(at 289.28 79.12 -90)
		(descr "Capacitor SMD 0603")
		(tags "capacitor 0603")
		(property "Reference" "C76"
			(at -3.31 -0.42 90)
			(layer "B.SilkS")
			(effects
				(font
					(size 0.7 0.7)
					(thickness 0.15)
				)
				(justify left bottom mirror)
			)
		)
		(property "Value" "C_22u_16V_0603"
			(at -1.42757 -1.770288 90)
			(layer "B.Fab")
			(effects
				(font
					(size 0.7 0.7)
					(thickness 0.15)
				)
				(justify left bottom mirror)
			)
		)
		(property "Datasheet" "https://product.samsungsem.com/mlcc/CL10A226MO7JZN.do"
			(at 0 0 270)
			(layer "F.Fab")
			(hide yes)
			(effects
				(font
					(size 1.27 1.27)
					(thickness 0.15)
				)
			)
		)
		(property "Author" "Antmicro"
			(at 210.16 368.4 0)
			(layer "B.Fab")
			(hide yes)
			(effects
				(font
					(size 1 1)
					(thickness 0.15)
				)
				(justify mirror)
			)
		)
		(property "Dielectric" ""
			(at 210.16 368.4 0)
			(layer "B.Fab")
			(hide yes)
			(effects
				(font
					(size 1 1)
					(thickness 0.15)
				)
				(justify mirror)
			)
		)
		(property "License" "Apache-2.0"
			(at 210.16 368.4 0)
			(layer "B.Fab")
			(hide yes)
			(effects
				(font
					(size 1 1)
					(thickness 0.15)
				)
				(justify mirror)
			)
		)
		(property "MPN" "CL10A226MO7JZNC"
			(at 210.16 368.4 0)
			(layer "B.Fab")
			(hide yes)
			(effects
				(font
					(size 1 1)
					(thickness 0.15)
				)
				(justify mirror)
			)
		)
		(property "Manufacturer" "Samsung Electro-Mechanics"
			(at 210.16 368.4 0)
			(layer "B.Fab")
			(hide yes)
			(effects
				(font
					(size 1 1)
					(thickness 0.15)
				)
				(justify mirror)
			)
		)
		(property "Public" "False"
			(at 210.16 368.4 0)
			(layer "B.Fab")
			(hide yes)
			(effects
				(font
					(size 1 1)
					(thickness 0.15)
				)
				(justify mirror)
			)
		)
		(property "Val" "22u"
			(at 210.16 368.4 0)
			(layer "B.Fab")
			(hide yes)
			(effects
				(font
					(size 1 1)
					(thickness 0.15)
				)
				(justify mirror)
			)
		)
		(property "Voltage" "16V"
			(at 210.16 368.4 0)
			(layer "B.Fab")
			(hide yes)
			(effects
				(font
					(size 1 1)
					(thickness 0.15)
				)
				(justify mirror)
			)
		)
		(sheetname "M.2 key M #2")
		(sheetfile "m2keym.kicad_sch")
		(attr smd)
		(fp_line
			(start 0.15 0.4)
			(end -0.15 0.4)
			(stroke
				(width 0.15)
				(type solid)
			)
			(layer "B.SilkS")
		)
		(fp_line
			(start 0.15 -0.4)
			(end -0.15 -0.4)
			(stroke
				(width 0.15)
				(type solid)
			)
			(layer "B.SilkS")
		)
		(fp_rect
			(start -1.25 0.65)
			(end 1.25 -0.65)
			(stroke
				(width 0.05)
				(type solid)
			)
			(fill no)
			(layer "B.CrtYd")
		)
		(fp_rect
			(start -0.8 0.4)
			(end 0.8 -0.4)
			(stroke
				(width 0.15)
				(type solid)
			)
			(fill no)
			(layer "B.Fab")
		)
		(pad "1" smd roundrect
			(at -0.7 0 270)
			(size 0.8 1)
			(layers "B.Cu" "B.Mask" "B.Paste")
			(roundrect_rratio 0.2)
			(net 1 "GND")
			(pintype "passive")
			(teardrops
				(best_length_ratio 0.2)
				(max_length 1)
				(best_width_ratio 0.9)
				(max_width 2)
				(curved_edges yes)
				(filter_ratio 0.9)
				(enabled yes)
				(allow_two_segments yes)
				(prefer_zone_connections yes)
			)
		)
		(pad "2" smd roundrect
			(at 0.7 0 270)
			(size 0.8 1)
			(layers "B.Cu" "B.Mask" "B.Paste")
			(roundrect_rratio 0.2)
			(net 970 "/M.2 key M #2/M2_3V3")
			(pintype "passive")
			(teardrops
				(best_length_ratio 0.2)
				(max_length 1)
				(best_width_ratio 0.9)
				(max_width 2)
				(curved_edges yes)
				(filter_ratio 0.9)
				(enabled yes)
				(allow_two_segments yes)
				(prefer_zone_connections yes)
			)
		)
	)
	(footprint "antmicro-footprints:R_0402_1005Metric"
		(layer "B.Cu")
		(at 139.05 169.16 -90)
		(descr "Resistor SMD 0402")
		(tags "resistor SMD 0402")
		(property "Reference" "R50"
			(at -3.9 13.5 90)
			(layer "B.SilkS")
			(effects
				(font
					(size 0.7 0.7)
					(thickness 0.15)
				)
				(justify left bottom mirror)
			)
		)
		(property "Value" "R_1k_0402"
			(at -1.011843 -1.772047 90)
			(layer "B.Fab")
			(effects
				(font
					(size 0.7 0.7)
					(thickness 0.15)
				)
				(justify left bottom mirror)
			)
		)
		(property "Datasheet" "https://www.bourns.com/docs/product-datasheets/cr.pdf"
			(at 0 0 270)
			(layer "F.Fab")
			(hide yes)
			(effects
				(font
					(size 1.27 1.27)
					(thickness 0.15)
				)
			)
		)
		(property "Author" "Antmicro"
			(at -30.11 308.21 0)
			(layer "B.Fab")
			(hide yes)
			(effects
				(font
					(size 1 1)
					(thickness 0.15)
				)
				(justify mirror)
			)
		)
		(property "License" "Apache-2.0"
			(at -30.11 308.21 0)
			(layer "B.Fab")
			(hide yes)
			(effects
				(font
					(size 1 1)
					(thickness 0.15)
				)
				(justify mirror)
			)
		)
		(property "MPN" "CR0402-FX-1001GLF"
			(at -30.11 308.21 0)
			(layer "B.Fab")
			(hide yes)
			(effects
				(font
					(size 1 1)
					(thickness 0.15)
				)
				(justify mirror)
			)
		)
		(property "Manufacturer" "Bourns"
			(at -30.11 308.21 0)
			(layer "B.Fab")
			(hide yes)
			(effects
				(font
					(size 1 1)
					(thickness 0.15)
				)
				(justify mirror)
			)
		)
		(property "Public" "False"
			(at -30.11 308.21 0)
			(layer "B.Fab")
			(hide yes)
			(effects
				(font
					(size 1 1)
					(thickness 0.15)
				)
				(justify mirror)
			)
		)
		(property "Tolerance" "1%"
			(at -30.11 308.21 0)
			(layer "B.Fab")
			(hide yes)
			(effects
				(font
					(size 1 1)
					(thickness 0.15)
				)
				(justify mirror)
			)
		)
		(property "Val" "1k"
			(at -30.11 308.21 0)
			(layer "B.Fab")
			(hide yes)
			(effects
				(font
					(size 1 1)
					(thickness 0.15)
				)
				(justify mirror)
			)
		)
		(sheetname "2xSFP+")
		(sheetfile "2xSFP+.kicad_sch")
		(attr smd)
		(fp_rect
			(start -0.925 0.47)
			(end 0.925 -0.47)
			(stroke
				(width 0.05)
				(type default)
			)
			(fill no)
			(layer "B.CrtYd")
		)
		(fp_rect
			(start -0.5 0.25)
			(end 0.5 -0.25)
			(stroke
				(width 0.15)
				(type solid)
			)
			(fill no)
			(layer "B.Fab")
		)
		(pad "1" smd roundrect
			(at -0.48 0 270)
			(size 0.59 0.64)
			(layers "B.Cu" "B.Mask" "B.Paste")
			(roundrect_rratio 0.25)
			(net 895 "Net-(J2B-RS0)")
			(pintype "passive")
			(teardrops
				(best_length_ratio 0.2)
				(max_length 1)
				(best_width_ratio 0.9)
				(max_width 2)
				(curved_edges yes)
				(filter_ratio 0.9)
				(enabled yes)
				(allow_two_segments yes)
				(prefer_zone_connections yes)
			)
		)
		(pad "2" smd roundrect
			(at 0.48 0 270)
			(size 0.59 0.64)
			(layers "B.Cu" "B.Mask" "B.Paste")
			(roundrect_rratio 0.25)
			(net 2 "+3V3")
			(pintype "passive")
			(teardrops
				(best_length_ratio 0.2)
				(max_length 1)
				(best_width_ratio 0.9)
				(max_width 2)
				(curved_edges yes)
				(filter_ratio 0.9)
				(enabled yes)
				(allow_two_segments yes)
				(prefer_zone_connections yes)
			)
		)
	)
	(footprint "antmicro-footprints:C_0402_1005Metric"
		(layer "B.Cu")
		(at 151.95 134.86 180)
		(descr "Capacitor SMD 0402")
		(tags "capacitor SMD 0402")
		(property "Reference" "C157"
			(at -3.7 -0.45 0)
			(layer "B.SilkS")
			(effects
				(font
					(size 0.7 0.7)
					(thickness 0.15)
				)
				(justify left bottom mirror)
			)
		)
		(property "Value" "C_100n_0402"
			(at -1.022927 -2.155213 0)
			(layer "B.Fab")
			(effects
				(font
					(size 0.7 0.7)
					(thickness 0.15)
				)
				(justify left bottom mirror)
			)
		)
		(property "Datasheet" "https://www.murata.com/products/productdetail?partno=GRM155R61H104KE14%23"
			(at 0 0 180)
			(layer "F.Fab")
			(hide yes)
			(effects
				(font
					(size 1.27 1.27)
					(thickness 0.15)
				)
			)
		)
		(property "Author" "Antmicro"
			(at 303.9 269.72 0)
			(layer "B.Fab")
			(hide yes)
			(effects
				(font
					(size 1 1)
					(thickness 0.15)
				)
				(justify mirror)
			)
		)
		(property "Dielectric" "X5R"
			(at 303.9 269.72 0)
			(layer "B.Fab")
			(hide yes)
			(effects
				(font
					(size 1 1)
					(thickness 0.15)
				)
				(justify mirror)
			)
		)
		(property "License" "Apache-2.0"
			(at 303.9 269.72 0)
			(layer "B.Fab")
			(hide yes)
			(effects
				(font
					(size 1 1)
					(thickness 0.15)
				)
				(justify mirror)
			)
		)
		(property "MPN" "GRM155R61H104KE14D"
			(at 303.9 269.72 0)
			(layer "B.Fab")
			(hide yes)
			(effects
				(font
					(size 1 1)
					(thickness 0.15)
				)
				(justify mirror)
			)
		)
		(property "Manufacturer" "Murata"
			(at 303.9 269.72 0)
			(layer "B.Fab")
			(hide yes)
			(effects
				(font
					(size 1 1)
					(thickness 0.15)
				)
				(justify mirror)
			)
		)
		(property "Public" "False"
			(at 303.9 269.72 0)
			(layer "B.Fab")
			(hide yes)
			(effects
				(font
					(size 1 1)
					(thickness 0.15)
				)
				(justify mirror)
			)
		)
		(property "Val" "100n"
			(at 303.9 269.72 0)
			(layer "B.Fab")
			(hide yes)
			(effects
				(font
					(size 1 1)
					(thickness 0.15)
				)
				(justify mirror)
			)
		)
		(property "Voltage" "50V"
			(at 303.9 269.72 0)
			(layer "B.Fab")
			(hide yes)
			(effects
				(font
					(size 1 1)
					(thickness 0.15)
				)
				(justify mirror)
			)
		)
		(sheetname "KR to SFI #1")
		(sheetfile "kr_sfi.kicad_sch")
		(attr smd)
		(fp_rect
			(start -0.925 0.47)
			(end 0.925 -0.47)
			(stroke
				(width 0.05)
				(type default)
			)
			(fill no)
			(layer "B.CrtYd")
		)
		(fp_line
			(start 0.504 0.25)
			(end -0.494 0.25)
			(stroke
				(width 0.15)
				(type solid)
			)
			(layer "B.Fab")
		)
		(fp_line
			(start 0.504 -0.248)
			(end 0.504 0.25)
			(stroke
				(width 0.15)
				(type solid)
			)
			(layer "B.Fab")
		)
		(fp_line
			(start -0.494 0.25)
			(end -0.494 -0.248)
			(stroke
				(width 0.15)
				(type solid)
			)
			(layer "B.Fab")
		)
		(fp_line
			(start -0.494 -0.248)
			(end 0.504 -0.248)
			(stroke
				(width 0.15)
				(type solid)
			)
			(layer "B.Fab")
		)
		(pad "1" smd roundrect
			(at -0.48 0 180)
			(size 0.59 0.64)
			(layers "B.Cu" "B.Mask" "B.Paste")
			(roundrect_rratio 0.25)
			(net 1 "GND")
			(pintype "passive")
			(teardrops
				(best_length_ratio 0.2)
				(max_length 1)
				(best_width_ratio 0.9)
				(max_width 2)
				(curved_edges yes)
				(filter_ratio 0.9)
				(enabled yes)
				(allow_two_segments yes)
				(prefer_zone_connections yes)
			)
		)
		(pad "2" smd roundrect
			(at 0.48 0 180)
			(size 0.59 0.64)
			(layers "B.Cu" "B.Mask" "B.Paste")
			(roundrect_rratio 0.25)
			(net 74 "+1V0")
			(pintype "passive")
			(teardrops
				(best_length_ratio 0.2)
				(max_length 1)
				(best_width_ratio 0.9)
				(max_width 2)
				(curved_edges yes)
				(filter_ratio 0.9)
				(enabled yes)
				(allow_two_segments yes)
				(prefer_zone_connections yes)
			)
		)
	)
	(footprint "antmicro-footprints:R_0402_1005Metric"
		(layer "B.Cu")
		(at 219.5 165.7 -90)
		(descr "Resistor SMD 0402")
		(tags "resistor SMD 0402")
		(property "Reference" "R160"
			(at -1.3 0.77 90)
			(layer "B.SilkS")
			(effects
				(font
					(size 0.7 0.7)
					(thickness 0.15)
				)
				(justify left bottom mirror)
			)
		)
		(property "Value" "R_1k_0402"
			(at 2.213157 -54.437047 90)
			(layer "B.Fab")
			(hide yes)
			(effects
				(font
					(size 0.7 0.7)
					(thickness 0.15)
				)
				(justify left bottom mirror)
			)
		)
		(property "Datasheet" "https://www.bourns.com/docs/product-datasheets/cr.pdf"
			(at 0 0 90)
			(layer "F.Fab")
			(hide yes)
			(effects
				(font
					(size 1.27 1.27)
					(thickness 0.15)
				)
			)
		)
		(property "Author" "Antmicro"
			(at 372.9 314.82 90)
			(layer "B.Fab")
			(hide yes)
			(effects
				(font
					(size 1 1)
					(thickness 0.15)
				)
				(justify mirror)
			)
		)
		(property "License" "Apache-2.0"
			(at 372.9 314.82 90)
			(layer "B.Fab")
			(hide yes)
			(effects
				(font
					(size 1 1)
					(thickness 0.15)
				)
				(justify mirror)
			)
		)
		(property "MPN" "CR0402-FX-1001GLF"
			(at 372.9 314.82 90)
			(layer "B.Fab")
			(hide yes)
			(effects
				(font
					(size 1 1)
					(thickness 0.15)
				)
				(justify mirror)
			)
		)
		(property "Manufacturer" "Bourns"
			(at 372.9 314.82 90)
			(layer "B.Fab")
			(hide yes)
			(effects
				(font
					(size 1 1)
					(thickness 0.15)
				)
				(justify mirror)
			)
		)
		(property "Public" "False"
			(at 372.9 314.82 90)
			(layer "B.Fab")
			(hide yes)
			(effects
				(font
					(size 1 1)
					(thickness 0.15)
				)
				(justify mirror)
			)
		)
		(property "Tolerance" "1%"
			(at 372.9 314.82 90)
			(layer "B.Fab")
			(hide yes)
			(effects
				(font
					(size 1 1)
					(thickness 0.15)
				)
				(justify mirror)
			)
		)
		(property "Val" "1k"
			(at 372.9 314.82 90)
			(layer "B.Fab")
			(hide yes)
			(effects
				(font
					(size 1 1)
					(thickness 0.15)
				)
				(justify mirror)
			)
		)
		(sheetname "Com Express 7 MGMT")
		(sheetfile "com_express_7_mgmt.kicad_sch")
		(attr smd)
		(fp_rect
			(start -0.925 0.47)
			(end 0.925 -0.47)
			(stroke
				(width 0.05)
				(type default)
			)
			(fill no)
			(layer "B.CrtYd")
		)
		(fp_rect
			(start -0.5 0.25)
			(end 0.5 -0.25)
			(stroke
				(width 0.15)
				(type solid)
			)
			(fill no)
			(layer "B.Fab")
		)
		(pad "1" smd roundrect
			(at -0.48 0 270)
			(size 0.59 0.64)
			(layers "B.Cu" "B.Mask" "B.Paste")
			(roundrect_rratio 0.25)
			(net 389 "Net-(J12D-~{BIOS_DIS1})")
			(pintype "passive")
			(teardrops
				(best_length_ratio 0.2)
				(max_length 1)
				(best_width_ratio 0.9)
				(max_width 2)
				(curved_edges yes)
				(filter_ratio 0.9)
				(enabled yes)
				(allow_two_segments yes)
				(prefer_zone_connections yes)
			)
		)
		(pad "2" smd roundrect
			(at 0.48 0 270)
			(size 0.59 0.64)
			(layers "B.Cu" "B.Mask" "B.Paste")
			(roundrect_rratio 0.25)
			(net 1 "GND")
			(pintype "passive")
			(teardrops
				(best_length_ratio 0.2)
				(max_length 1)
				(best_width_ratio 0.9)
				(max_width 2)
				(curved_edges yes)
				(filter_ratio 0.9)
				(enabled yes)
				(allow_two_segments yes)
				(prefer_zone_connections yes)
			)
		)
	)
	(footprint "antmicro-footprints:TP_SMD_0.75mm"
		(layer "B.Cu")
		(at 194.35 151.2 -45)
		(property "Reference" "TP19"
			(at -0.388909 -0.742462 45)
			(layer "B.SilkS")
			(effects
				(font
					(size 0.7 0.7)
					(thickness 0.15)
				)
				(justify right top mirror)
			)
		)
		(property "Value" "TP_0.75mm_SMD"
			(at 3.225 -53.865 135)
			(layer "B.Fab")
			(hide yes)
			(effects
				(font
					(size 0.7 0.7)
					(thickness 0.15)
				)
				(justify left bottom mirror)
			)
		)
		(property "Author" "Antmicro"
			(at 428.6 339.52 135)
			(layer "B.Fab")
			(hide yes)
			(effects
				(font
					(size 1 1)
					(thickness 0.15)
				)
				(justify mirror)
			)
		)
		(property "License" "Apache-2.0"
			(at 428.6 339.52 135)
			(layer "B.Fab")
			(hide yes)
			(effects
				(font
					(size 1 1)
					(thickness 0.15)
				)
				(justify mirror)
			)
		)
		(property "MPN" ""
			(at 428.6 339.52 135)
			(layer "B.Fab")
			(hide yes)
			(effects
				(font
					(size 1 1)
					(thickness 0.15)
				)
				(justify mirror)
			)
		)
		(property "Manufacturer" ""
			(at 428.6 339.52 135)
			(layer "B.Fab")
			(hide yes)
			(effects
				(font
					(size 1 1)
					(thickness 0.15)
				)
				(justify mirror)
			)
		)
		(property "Public" "False"
			(at 428.6 339.52 135)
			(layer "B.Fab")
			(hide yes)
			(effects
				(font
					(size 1 1)
					(thickness 0.15)
				)
				(justify mirror)
			)
		)
		(sheetname "Com Express 7 Interfaces")
		(sheetfile "com_express_7_interfaces.kicad_sch")
		(attr exclude_from_pos_files exclude_from_bom)
		(fp_circle
			(center 0 0)
			(end 0.475 0)
			(stroke
				(width 0.05)
				(type default)
			)
			(fill no)
			(layer "B.CrtYd")
		)
		(pad "1" smd circle
			(at 0 0 315)
			(size 0.75 0.75)
			(layers "B.Cu" "B.Mask")
			(net 489 "Net-(J12K-10G_SDP1)")
			(pinfunction "1")
			(pintype "passive")
			(teardrops
				(best_length_ratio 0.4)
				(max_length 1)
				(best_width_ratio 0.9)
				(max_width 2)
				(curved_edges yes)
				(filter_ratio 0.9)
				(enabled yes)
				(allow_two_segments yes)
				(prefer_zone_connections yes)
			)
		)
	)
	(footprint "antmicro-footprints:C_0402_1005Metric"
		(layer "B.Cu")
		(at 116.9 85.910001)
		(descr "Capacitor SMD 0402")
		(tags "capacitor SMD 0402")
		(property "Reference" "C17"
			(at -1.05 -0.500001 0)
			(layer "B.SilkS")
			(effects
				(font
					(size 0.7 0.7)
					(thickness 0.15)
				)
				(justify right bottom mirror)
			)
		)
		(property "Value" "C_100n_0402"
			(at -1.022927 -2.155213 0)
			(layer "B.Fab")
			(effects
				(font
					(size 0.7 0.7)
					(thickness 0.15)
				)
				(justify right bottom mirror)
			)
		)
		(property "Datasheet" "https://www.murata.com/products/productdetail?partno=GRM155R61H104KE14%23"
			(at 0 0 0)
			(layer "F.Fab")
			(hide yes)
			(effects
				(font
					(size 1.27 1.27)
					(thickness 0.15)
				)
			)
		)
		(property "Author" "Antmicro"
			(at 0 0 0)
			(layer "B.Fab")
			(hide yes)
			(effects
				(font
					(size 1 1)
					(thickness 0.15)
				)
				(justify mirror)
			)
		)
		(property "Dielectric" "X5R"
			(at 0 0 0)
			(layer "B.Fab")
			(hide yes)
			(effects
				(font
					(size 1 1)
					(thickness 0.15)
				)
				(justify mirror)
			)
		)
		(property "License" "Apache-2.0"
			(at 0 0 0)
			(layer "B.Fab")
			(hide yes)
			(effects
				(font
					(size 1 1)
					(thickness 0.15)
				)
				(justify mirror)
			)
		)
		(property "MPN" "GRM155R61H104KE14D"
			(at 0 0 0)
			(layer "B.Fab")
			(hide yes)
			(effects
				(font
					(size 1 1)
					(thickness 0.15)
				)
				(justify mirror)
			)
		)
		(property "Manufacturer" "Murata"
			(at 0 0 0)
			(layer "B.Fab")
			(hide yes)
			(effects
				(font
					(size 1 1)
					(thickness 0.15)
				)
				(justify mirror)
			)
		)
		(property "Public" "False"
			(at 0 0 0)
			(layer "B.Fab")
			(hide yes)
			(effects
				(font
					(size 1 1)
					(thickness 0.15)
				)
				(justify mirror)
			)
		)
		(property "Val" "100n"
			(at 0 0 0)
			(layer "B.Fab")
			(hide yes)
			(effects
				(font
					(size 1 1)
					(thickness 0.15)
				)
				(justify mirror)
			)
		)
		(property "Voltage" "50V"
			(at 0 0 0)
			(layer "B.Fab")
			(hide yes)
			(effects
				(font
					(size 1 1)
					(thickness 0.15)
				)
				(justify mirror)
			)
		)
		(sheetname "2xUSB3.0+RJ45")
		(sheetfile "usb3+rj45.kicad_sch")
		(attr smd)
		(fp_rect
			(start -0.925 0.47)
			(end 0.925 -0.47)
			(stroke
				(width 0.05)
				(type default)
			)
			(fill no)
			(layer "B.CrtYd")
		)
		(fp_line
			(start -0.494 -0.248)
			(end 0.504 -0.248)
			(stroke
				(width 0.15)
				(type solid)
			)
			(layer "B.Fab")
		)
		(fp_line
			(start -0.494 0.25)
			(end -0.494 -0.248)
			(stroke
				(width 0.15)
				(type solid)
			)
			(layer "B.Fab")
		)
		(fp_line
			(start 0.504 -0.248)
			(end 0.504 0.25)
			(stroke
				(width 0.15)
				(type solid)
			)
			(layer "B.Fab")
		)
		(fp_line
			(start 0.504 0.25)
			(end -0.494 0.25)
			(stroke
				(width 0.15)
				(type solid)
			)
			(layer "B.Fab")
		)
		(pad "1" smd roundrect
			(at -0.48 0)
			(size 0.59 0.64)
			(layers "B.Cu" "B.Mask" "B.Paste")
			(roundrect_rratio 0.25)
			(net 1 "GND")
			(pintype "passive")
			(teardrops
				(best_length_ratio 0.2)
				(max_length 1)
				(best_width_ratio 0.9)
				(max_width 2)
				(curved_edges yes)
				(filter_ratio 0.9)
				(enabled yes)
				(allow_two_segments yes)
				(prefer_zone_connections yes)
			)
		)
		(pad "2" smd roundrect
			(at 0.48 0)
			(size 0.59 0.64)
			(layers "B.Cu" "B.Mask" "B.Paste")
			(roundrect_rratio 0.25)
			(net 52 "+5V")
			(pintype "passive")
			(teardrops
				(best_length_ratio 0.2)
				(max_length 1)
				(best_width_ratio 0.9)
				(max_width 2)
				(curved_edges yes)
				(filter_ratio 0.9)
				(enabled yes)
				(allow_two_segments yes)
				(prefer_zone_connections yes)
			)
		)
	)
)
